# S9S_MB_2U (Grand Teton) — schematic parts with pin connectivity, parts 5876–5876 of 6093; source: Cadence DE-HDL packaged netlist (pstxprt.dat, pstxnet.dat, pstchip.dat)

U1  SOCKET4677_AZIF0045P001C01CS  SOCKET4677_AZIF0045-P001C01CS IO  pkg SOCKET4677_82X64-5XA_H466  page 44  (pins 1963-2289 of 4677)
  CH81  VCCIN318  POWER  = PVCCIN_CPU1
  CH83  VSS731  POWER  = GND
  CH85  VSS732  POWER  = GND
  CH87  VSS733  POWER  = GND
  CH89  VSS734  POWER  = GND
  CH91  VCCIN319  POWER  = PVCCIN_CPU1
  CJ1  UPI1_RX_DN19  IN  = UPI_CPU0_CPU1_P0P1_DN<19>
  CJ3  VCCINFAON2  POWER  = PVCCINFAON_CPU1
  CJ5  UPI1_TX_DN18  OUT  = UPI_CPU1_CPU0_P1P0_DN<18>
  CJ7  VCCINFAON3  POWER  = PVCCINFAON_CPU1
  CJ9  PE1_RX_DP2  IN  = P5E_CPU1_PE1_RX_DP<2>
  CJ11  VCCINFAON45  POWER  = PVCCINFAON_CPU1
  CJ13  PE1_TX_DN3  OUT  = P5E_CPU1_PE1_TX_DN<3>
  CJ15  VCCINFAON1  POWER  = PVCCINFAON_CPU1
  CJ17  DMI_TX_DN5  OUT  = TP_DMI_CPU1_PCH_TX_DN<5>
  CJ19  VCCINFAON46  POWER  = PVCCINFAON_CPU1
  CJ21  RSVD101  BI  = TP_CPU1_IBL_GRST_WARN_CPU1_N
  CJ23  RSVD102  BI  = TP_I2C_S3M_RTC_CPU1_SDA
  CJ25  RSVD103  BI  = TP_I2C_S3M_RTC_CPU1_RST_N
  CJ60  VSS736  POWER  = GND
  CJ62  RSVD104  BI  = CPU1_RSVD<98>
  CJ64  TEST_1  BI  = PU_S3M_CPU1_CPLD_CONFD
  CJ66  RSVD105  BI  = TP_SGPIO_S3M_CPU1_GSXDLOAD
  CJ68  RSVD106  BI  = NC_CPU1_MDFI_DIE11_NS0
  CJ70  RSVD107  BI  = NC_CPU1_MDFI_DIE11_EW0
  CJ72  RSVD108  BI  = PUD_XTAL_CPU1_MODE1
  CJ74  UPI3_TX_DN21  OUT  = NC
  CJ76  VSS383  POWER  = GND
  CJ78  UPI3_TX_DP17  OUT  = NC
  CJ80  VSS737  POWER  = GND
  CJ82  VCCIN320  POWER  = PVCCIN_CPU1
  CJ84  VCCIN321  POWER  = PVCCIN_CPU1
  CJ86  VCCIN322  POWER  = PVCCIN_CPU1
  CJ88  VCCIN323  POWER  = PVCCIN_CPU1
  CJ90  VCCIN324  POWER  = PVCCIN_CPU1
  CK2  UPI1_RX_DP19  IN  = UPI_CPU0_CPU1_P0P1_DP<19>
  CK4  VSS396  POWER  = GND
  CK6  UPI1_TX_DP18  OUT  = UPI_CPU1_CPU0_P1P0_DP<18>
  CK8  VSS746  POWER  = GND
  CK10  PE1_RX_DN2  IN  = P5E_CPU1_PE1_RX_DN<2>
  CK12  VSS740  POWER  = GND
  CK14  PE1_TX_DN2  OUT  = P5E_CPU1_PE1_TX_DN<2>
  CK16  VSS741  POWER  = GND
  CK18  DMI_TX_DN6  OUT  = TP_DMI_CPU1_PCH_TX_DN<6>
  CK20  VSS742  POWER  = GND
  CK22  RSVD109  BI  = TP_FM_SYS_RST_CPU1_N
  CK24  RSVD110  BI  = TP_FM_IBL_PWRBTN_CPU1_N
  CK26  VSS743  POWER  = GND
  CK61  RSVD111  BI  = TP_CPU1_SPARE8
  CK63  VSS744  POWER  = GND
  CK65  TEST_2  BI  = FM_S3M_CPU1_CPLD_CONFIG_N
  CK67  RSVD112  BI  = NC_CPU1_MDFI_DIE11_NS1
  CK69  VSS745  POWER  = GND
  CK71  UPI3_AC_COUPLING  IN  = PU_CPU1_UPI3_AC_COUPLING
  CK73  VCCFA_EHV_FIVRA35  POWER  = PVCCFA_EHV_FIVRA_CPU1
  CK75  UPI3_TX_DP21  OUT  = NC
  CK77  UPI3_TX_DN16  OUT  = NC
  CK79  VCCFA_EHV_FIVRA36  POWER  = PVCCFA_EHV_FIVRA_CPU1
  CK81  VSS749  POWER  = GND
  CK83  VCCIN325  POWER  = PVCCIN_CPU1
  CK85  VCCIN326  POWER  = PVCCIN_CPU1
  CK87  VCCIN327  POWER  = PVCCIN_CPU1
  CK89  VCCIN328  POWER  = PVCCIN_CPU1
  CK91  VCCIN329  POWER  = PVCCIN_CPU1
  CL1  VSS750  POWER  = GND
  CL3  UPI1_RX_DN18  IN  = UPI_CPU0_CPU1_P0P1_DN<18>
  CL5  VSS754  POWER  = GND
  CL7  UPI1_TX_DP17  OUT  = UPI_CPU1_CPU0_P1P0_DP<17>
  CL9  VSS760  POWER  = GND
  CL11  PE1_RX_DN1  IN  = P5E_CPU1_PE1_RX_DN<1>
  CL13  VSS751  POWER  = GND
  CL15  PE1_TX_DP2  OUT  = P5E_CPU1_PE1_TX_DP<2>
  CL17  VSS752  POWER  = GND
  CL19  DMI_TX_DP6  OUT  = TP_DMI_CPU1_PCH_TX_DP<6>
  CL21  RSVD113  BI  = CPU1_RSVD<107>
  CL23  RSVD114  BI  = TP_I2C_S3M_RTC_CPU1_SCL
  CL25  PMSYNC1  BI  = TP_H_SBLINK2_CPU1_PMSYNC
  CL60  RSVD115  BI  = TP_CPU1_SPARE7
  CL62  VSS755  POWER  = GND
  CL64  RSVD116  BI  = CPU1_RSVD<110>
  CL66  RSVD117  BI  = TP_CPU1_SSC_SYNC
  CL68  RSVD118  BI  = NC_CPU1_PE3_APROBE<0>
  CL70  RSVD119  BI  = TP_CPU1_SPARE12
  CL72  RSVD120  BI  = PUD_XTAL_CPU1_MODE0
  CL74  VSS756  POWER  = GND
  CL76  UPI3_TX_DP18  OUT  = NC
  CL78  VSS757  POWER  = GND
  CL80  VSS758  POWER  = GND
  CL82  VSS759  POWER  = GND
  CL84  VCCIN330  POWER  = PVCCIN_CPU1
  CL86  VCCIN331  POWER  = PVCCIN_CPU1
  CL88  VCCIN332  POWER  = PVCCIN_CPU1
  CL90  VCCIN333  POWER  = PVCCIN_CPU1
  CM2  UPI1_RX_DP18  IN  = UPI_CPU0_CPU1_P0P1_DP<18>
  CM4  VSS764  POWER  = GND
  CM6  UPI1_TX_DN17  OUT  = UPI_CPU1_CPU0_P1P0_DN<17>
  CM8  VSS769  POWER  = GND
  CM10  PE1_RX_DP1  IN  = P5E_CPU1_PE1_RX_DP<1>
  CM12  VSS761  POWER  = GND
  CM14  PE1_TX_DP1  OUT  = P5E_CPU1_PE1_TX_DP<1>
  CM16  VSS436  POWER  = GND
  CM18  DMI_TX_DP7  OUT  = TP_DMI_CPU1_PCH_TX_DP<7>
  CM20  VSS762  POWER  = GND
  CM22  VSS438  POWER  = GND
  CM24  VSS763  POWER  = GND
  CM26  PMDOWN2  BI  = TP_H_SBLINK3_CPU1_PMDOWN
  CM61  VSS765  POWER  = GND
  CM63  RSVD121  BI  = CPU1_RSVD<115>
  CM65  VSS766  POWER  = GND
  CM67  VSS767  POWER  = GND
  CM69  RSVD122  BI  = NC_CPU1_PE3_APROBE<1>
  CM71  PIROM_SDA  BI  = SMB_S3M_CPU1_PIROM_3V3AUX_SDA_1
  CM73  VCCFA_EHV_FIVRA37  POWER  = PVCCFA_EHV_FIVRA_CPU1
  CM75  UPI3_TX_DN18  OUT  = NC
  CM77  UPI3_TX_DP16  OUT  = NC
  CM79  VSS768  POWER  = GND
  CM81  VSS770  POWER  = GND
  CM83  VSS771  POWER  = GND
  CM85  VSS772  POWER  = GND
  CM87  VCCIN334  POWER  = PVCCIN_CPU1
  CM89  VCCIN339  POWER  = PVCCIN_CPU1
  CM91  VCCIN335  POWER  = PVCCIN_CPU1
  CN1  UPI1_RX_DN17  IN  = UPI_CPU0_CPU1_P0P1_DN<17>
  CN3  VCCINFAON6  POWER  = PVCCINFAON_CPU1
  CN5  UPI1_TX_DN16  OUT  = UPI_CPU1_CPU0_P1P0_DN<16>
  CN7  VCCINFAON9  POWER  = PVCCINFAON_CPU1
  CN9  PE1_RX_DP0  IN  = P5E_CPU1_PE1_RX_DP<0>
  CN11  VCCINFAON4  POWER  = PVCCINFAON_CPU1
  CN13  PE1_TX_DN1  OUT  = P5E_CPU1_PE1_TX_DN<1>
  CN15  VCCINFAON5  POWER  = PVCCINFAON_CPU1
  CN17  DMI_TX_DN7  OUT  = TP_DMI_CPU1_PCH_TX_DN<7>
  CN19  VCCINFAON47  POWER  = PVCCINFAON_CPU1
  CN21  RSVD123  BI  = TP_FM_IBL_SLPS4_CPU1_R_N
  CN23  RSVD124  BI  = NC_FM_IBL_ADR_ACK_CPU1
  CN25  PMSYNC0  BI  = H_CPU0_PMDOWN_CPU1
  CN60  RSVD125  BI  = NC_CPU1_LGSSPARE1
  CN62  RSVD126  BI  = CPU1_RSVD<120>
  CN64  VCCINFAON7  POWER  = PVCCINFAON_CPU1
  CN66  VCCINFAON8  POWER  = PVCCINFAON_CPU1
  CN68  VSS773  POWER  = GND
  CN70  VSS774  POWER  = GND
  CN72  VSS775  POWER  = GND
  CN74  VSS777  POWER  = GND
  CN76  VSS471  POWER  = GND
  CN78  VCCFA_EHV_FIVRA38  POWER  = PVCCFA_EHV_FIVRA_CPU1
  CN80  UPI3_RX_DN21  IN  = GND
  CN82  UPI3_RX_DP20  IN  = GND
  CN84  VSS778  POWER  = GND
  CN86  VSS779  POWER  = GND
  CN88  VCCIN336  POWER  = PVCCIN_CPU1
  CN90  VCCIN337  POWER  = PVCCIN_CPU1
  CP2  UPI1_RX_DP17  IN  = UPI_CPU0_CPU1_P0P1_DP<17>
  CP4  VSS782  POWER  = GND
  CP6  UPI1_TX_DP16  OUT  = UPI_CPU1_CPU0_P1P0_DP<16>
  CP8  VSS785  POWER  = GND
  CP10  PE1_RX_DN0  IN  = P5E_CPU1_PE1_RX_DN<0>
  CP12  VSS780  POWER  = GND
  CP14  PE1_TX_DN0  OUT  = P5E_CPU1_PE1_TX_DN<0>
  CP16  VSS478  POWER  = GND
  CP18  VSS781  POWER  = GND
  CP20  PMFAST_WAKE_N  BI  = H_CPU1_PM_FAST_WAKE_N
  CP22  RSVD127  BI  = TP_JTAG_CPU1_PLD_TDO_R
  CP24  RSVD128  BI  = NC_FM_IBL_ADR_COMPLETE_CPU1_R
  CP26  PMDOWN1  BI  = TP_H_SBLINK2_CPU1_PMDOWN
  CP61  RSVD129  BI  = NC_CPU1_LGSSPARE5
  CP63  VCCINFAON48  POWER  = PVCCINFAON_CPU1
  CP65  VCCINFAON10  POWER  = PVCCINFAON_CPU1
  CP67  VCCINFAON11  POWER  = PVCCINFAON_CPU1
  CP69  RSVD130  BI  = NC_CPU1_UPI3_APROBE<0>
  CP71  PIROM_AD2  IN  = PD_PIROM_CPU1_ADDR2
  CP73  VCCFA_EHV_FIVRA39  POWER  = PVCCFA_EHV_FIVRA_CPU1
  CP75  VSS783  POWER  = GND
  CP77  VSS784  POWER  = GND
  CP79  VSS493  POWER  = GND
  CP81  UPI3_RX_DN20  IN  = GND
  CP83  VSS786  POWER  = GND
  CP85  PE3_TX_DN15  OUT  = P5E_CPU1_PE3_TX_DN<15>
  CP87  VSS787  POWER  = GND
  CP89  VCCIN338  POWER  = PVCCIN_CPU1
  CP91  VSS788  POWER  = GND
  CR1  VSS789  POWER  = GND
  CR3  UPI1_RX_DN16  IN  = UPI_CPU0_CPU1_P0P1_DN<16>
  CR5  VSS794  POWER  = GND
  CR7  UPI1_TX_DP15  OUT  = UPI_CPU1_CPU0_P1P0_DP<15>
  CR9  VSS801  POWER  = GND
  CR11  VSS790  POWER  = GND
  CR13  VSS792  POWER  = GND
  CR15  PE1_TX_DP0  OUT  = P5E_CPU1_PE1_TX_DP<0>
  CR17  VSS793  POWER  = GND
  CR19  PMSYNC4  BI  = TP_H_SBLINK5_CPU1_PMSYNC
  CR21  RSVD131  BI  = TP_FM_IBL_SLPS3_CPU1_R_N
  CR23  RSVD132  BI  = CPU1_RSVD<126>
  CR25  RSVD133  BI  = NC_CPU1_VIEWPIN_GNR2
  CR60  RSVD134  BI  = NC_CPU1_LGSSPARE0
  CR62  VSS795  POWER  = GND
  CR64  VSS796  POWER  = GND
  CR66  VCCINFAON54  POWER  = PVCCINFAON_CPU1
  CR68  RSVD135  BI  = NC_CPU1_UPI3_APROBE<1>
  CR70  PIROM_AD0  IN  = PU_PIROM_CPU1_ADDR0
  CR72  PIROM_SM_WP  IN  = PU_PIROM_CPU1_SM_WP
  CR74  UPI3_TX_DN15  OUT  = NC
  CR76  UPI3_TX_DP14  OUT  = NC
  CR78  VSS514  POWER  = GND
  CR80  UPI3_RX_DP21  IN  = GND
  CR82  UPI3_RX_DN18  IN  = GND
  CR84  VSS797  POWER  = GND
  CR86  PE3_TX_DP15  OUT  = P5E_CPU1_PE3_TX_DP<15>
  CR88  VSS800  POWER  = GND
  CR90  VSS803  POWER  = GND
  CT2  UPI1_RX_DP16  IN  = UPI_CPU0_CPU1_P0P1_DP<16>
  CT4  VSS526  POWER  = GND
  CT6  UPI1_TX_DN15  OUT  = UPI_CPU1_CPU0_P1P0_DN<15>
  CT8  VSS534  POWER  = GND
  CT10  VSS804  POWER  = GND
  CT12  VSS805  POWER  = GND
  CT14  PE2_TX_DP0  OUT  = P5E_CPU1_PE2_TX_DP<0>
  CT16  VSS521  POWER  = GND
  CT18  DDR4567_SPDSDA  BI  = I3C_SPD_DDREFGH_CPU1_SDA
  CT20  TXT_PLTEN  IN  = PD_CPU1_TXT_PLTEN
  CT22  RSVD136  BI  = TP_JTAG_CPU1_PLD_TDI
  CT24  RSVD137  BI  = NC_FM_IBL_ADR_TRIGGER_CPU1_R
  CT26  RSVD138  BI  = NC_CPU1_VIEWPIN_GNR0
  CT61  SOCKET_ID2  IN  = PU_CPU1_SOCKET_ID2
  CT63  VCCINFAON49  POWER  = PVCCINFAON_CPU1
  CT65  VCCINFAON12  POWER  = PVCCINFAON_CPU1
  CT67  VCCINFAON13  POWER  = PVCCINFAON_CPU1
  CT69  VSS810  POWER  = GND
  CT71  PIROM_AD1  IN  = PD_PIROM_CPU1_ADDR1
  CT73  VSS811  POWER  = GND
  CT75  UPI3_TX_DN14  OUT  = NC
  CT77  VCCFA_EHV_FIVRA40  POWER  = PVCCFA_EHV_FIVRA_CPU1
  CT79  UPI3_RX_DN22  IN  = GND
  CT81  VSS812  POWER  = GND
  CT83  UPI3_RX_DP18  IN  = GND
  CT85  VCCFA_EHV_FIVRA41  POWER  = PVCCFA_EHV_FIVRA_CPU1
  CT87  PE3_TX_DN14  OUT  = P5E_CPU1_PE3_TX_DN<14>
  CT89  VSS537  POWER  = GND
  CT91  PE3_RX_DP15  IN  = P5E_CPU1_PE3_RX_DP<15>
  CU1  UPI1_RX_DP15  IN  = UPI_CPU0_CPU1_P0P1_DP<15>
  CU3  VCCINFAON16  POWER  = PVCCINFAON_CPU1
  CU5  UPI1_TX_DN14  OUT  = UPI_CPU1_CPU0_P1P0_DN<14>
  CU7  VCCINFAON18  POWER  = PVCCINFAON_CPU1
  CU9  PE2_RX_DN0  IN  = P5E_CPU1_PE2_RX_DN<0>
  CU11  VCCINFAON14  POWER  = PVCCINFAON_CPU1
  CU13  PE2_TX_DN0  OUT  = P5E_CPU1_PE2_TX_DN<0>
  CU15  VCCINFAON15  POWER  = PVCCINFAON_CPU1
  CU17  DDR4567_SPDSCL  OUT  = I3C_SPD_DDREFGH_CPU1_SCL
  CU19  VSS813  POWER  = GND
  CU21  VSS814  POWER  = GND
  CU23  VSS815  POWER  = GND
  CU25  VSS544  POWER  = GND
  CU60  VSS816  POWER  = GND
  CU62  RSVD139  BI  = NC_CPU1_LGSSPARE2
  CU64  VCCINFAON17  POWER  = PVCCINFAON_CPU1
  CU66  VSS818  POWER  = GND
  CU68  VSS819  POWER  = GND
  CU70  PIROM_SCL  IN  = SMB_S3M_CPU1_PIROM_3V3AUX_SCL_1
  CU72  VSS553  POWER  = GND
  CU74  UPI3_TX_DP15  OUT  = NC
  CU76  UPI3_TX_DN13  OUT  = NC
  CU78  VSS554  POWER  = GND
  CU80  UPI3_RX_DP22  IN  = GND
  CU82  UPI3_RX_DN17  IN  = GND
  CU84  VSS822  POWER  = GND
  CU86  PE3_TX_DP14  OUT  = P5E_CPU1_PE3_TX_DP<14>
  CU88  VSS823  POWER  = GND
  CU90  PE3_RX_DN15  IN  = P5E_CPU1_PE3_RX_DN<15>
  CV2  UPI1_RX_DN15  IN  = UPI_CPU0_CPU1_P0P1_DN<15>
  CV4  VSS825  POWER  = GND
  CV6  UPI1_TX_DP14  OUT  = UPI_CPU1_CPU0_P1P0_DP<14>
  CV8  VSS827  POWER  = GND
  CV10  PE2_RX_DP0  IN  = P5E_CPU1_PE2_RX_DP<0>
  CV12  VSS824  POWER  = GND
  CV14  PE2_TX_DN1  OUT  = P5E_CPU1_PE2_TX_DN<1>
  CV16  VSS558  POWER  = GND
  CV18  PMDOWN4  BI  = TP_H_SBLINK5_CPU1_PMDOWN
  CV20  PLT_AUX_PWRGOOD  IN  = PWRGD_PLT_AUX_CPU1_LVT3
  CV22  RSVD140  BI  = TP_JTAG_CPU1_PLD_TMS
  CV24  RSVD141  BI  = CPU1_RSVD<135>
  CV26  VSS562  POWER  = GND
  CV61  VCCINFAON50  POWER  = PVCCINFAON_CPU1
  CV63  VCCINFAON51  POWER  = PVCCINFAON_CPU1
  CV65  VCCINFAON19  POWER  = PVCCINFAON_CPU1
  CV67  VCCINFAON20  POWER  = PVCCINFAON_CPU1
  CV69  RSVD142  BI  = NC_UART_IBL_CPU1_TXD
  CV71  RSVD143  BI  = NC_UART_IBL_CPU1_CTS
  CV73  UPI3_TX_DN22  OUT  = NC
  CV75  VSS826  POWER  = GND
  CV77  UPI3_TX_DP13  OUT  = NC
  CV79  VSS571  POWER  = GND
  CV81  UPI3_RX_DP19  IN  = GND
  CV83  VSS828  POWER  = GND
  CV85  PE3_TX_DN13  OUT  = P5E_CPU1_PE3_TX_DN<13>
  CV87  VSS831  POWER  = GND
  CV89  PE3_RX_DN14  IN  = P5E_CPU1_PE3_RX_DN<14>
  CV91  VSS833  POWER  = GND
  CW1  VSS834  POWER  = GND
  CW3  UPI1_RX_DP14  IN  = UPI_CPU0_CPU1_P0P1_DP<14>
  CW5  VSS838  POWER  = GND
  CW7  UPI1_TX_DP13  OUT  = UPI_CPU1_CPU0_P1P0_DP<13>
  CW9  VSS850  POWER  = GND
  CW11  PE2_RX_DP1  IN  = P5E_CPU1_PE2_RX_DP<1>
  CW13  VSS836  POWER  = GND
  CW15  PE2_TX_DP1  OUT  = P5E_CPU1_PE2_TX_DP<1>
  CW17  VSS837  POWER  = GND
  CW19  UPI1_AC_COUPLING  IN  = PU_CPU1_UPI1_AC_COUPLING
  CW21  RSVD144  BI  = TP_FM_IBL_SLPS5_CPU1_R_N
  CW23  RSVD145  BI  = CPU1_RSVD<139>
  CW25  RSVD146  BI  = CPU1_RSVD<140>
  CW27  BCLK3_DN  IN  = CLK_100M_DB2000_CPU1_BCLK3_DN
  CW29  BCLK1_DP  IN  = CLK_100M_DB2000_CPU1_BCLK1_DP
  CW31  XTAL_CLK_DN  IN  = CLK_25M_NSSC_CPU1_DN
  CW33  VSS583  POWER  = GND
  CW35  VCCD_HV21  POWER  = PVCCD_HV_CPU1
  CW37  VCCD_HV22  POWER  = PVCCD_HV_CPU1
  CW39  PMDOWN0  IN  = H_CPU0_PMSYNC_CPU1
  CW41  RSVD147  BI  = NC_CPU1_HBM1_VIEWDIG1
  CW43  RSVD148  BI  = TP_CPU1_SPARE6
  CW45  DDR67_DRAM_PWR_OK  IN  = PWRGD_DRAMPWRGD_CPU1_GH_LVC1_R
  CW48  DDR5_ALERT_N  IN  = M_F_CPU1_ALERT_N
  CW50  DDR6_ALERT_N  IN  = M_G_CPU1_ALERT_N
  CW52  VCCD_HV23  POWER  = PVCCD_HV_CPU1
  CW54  VCCD_HV24  POWER  = PVCCD_HV_CPU1
  CW56  VCCD_HV25  POWER  = PVCCD_HV_CPU1
  CW58  RSVD149  BI  = NC_CPU1_VIEWPIN_GNR1
  CW60  SOCKET_ID0  IN  = PU_CPU1_SOCKET_ID0
  CW62  VCCINFAON52  POWER  = PVCCINFAON_CPU1
